# T6G (Grand Teton) — schematic netlist excerpt (pin names and nets, part order shuffled) for the footprints in the layout excerpt that follows; sources: Cadence DE-HDL packaged netlist, KiCad conversion of 04192023_DAF0TMB3IC0_F0TG_MB_C_brd_V02_OCP.brd

R1057  Q_RES  1K 1% EMPTY  pkg 0201LF  page 298 : A = P1V8_CPU0_RT_1D ; B = RT_CPU0_P2_ADDR2
R1522  Q_RES  0 5% CHIP  pkg 0402LF  page 247 : A = HP_LVC3_OCP_V3_2_R_EN ; B = P12V_OCP_V3_2_BUF_EN_R
R2219  Q_RES  267K 1% EMPTY  pkg 0402LF  page 268 : A = P12V_AUX ; B = A_P12V_STBY_ADR_TRIGGER

(kicad_pcb
	(version 20260206)
	(generator "pcbnew")
	(generator_version "10.0")
	(general
		(thickness 1.6)
		(legacy_teardrops no)
	)
	(paper "A4")
	(title_block
		(title "04192023_DAF0TMB3IC0_F0TG_MB_C_brd_V02_OCP.brd")
		(comment 1 "Grand Teton / footprints 574-576 of 8354")
	)
	(layers
		(0 "F.Cu" signal "TOP")
		(4 "In1.Cu" signal "GND")
		(6 "In2.Cu" signal "IN1")
		(8 "In3.Cu" signal "GND1")
		(10 "In4.Cu" signal "IN2")
		(12 "In5.Cu" signal "GND2")
		(14 "In6.Cu" signal "IN3")
		(16 "In7.Cu" signal "GND3")
		(18 "In8.Cu" signal "VCC")
		(20 "In9.Cu" signal "VCC1")
		(22 "In10.Cu" signal "GND4")
		(24 "In11.Cu" signal "IN4")
		(26 "In12.Cu" signal "GND5")
		(28 "In13.Cu" signal "IN5")
		(30 "In14.Cu" signal "GND6")
		(32 "In15.Cu" signal "IN6")
		(34 "In16.Cu" signal "GND7")
		(2 "B.Cu" signal "BOTTOM")
		(9 "F.Adhes" user "F.Adhesive")
		(11 "B.Adhes" user "B.Adhesive")
		(13 "F.Paste" user "Package Geometry/Pastemask Top")
		(15 "B.Paste" user "Package Geometry/Pastemask Bottom")
		(5 "F.SilkS" user "Ref Des/Silkscreen Top")
		(7 "B.SilkS" user "Ref Des/Silkscreen Bottom")
		(1 "F.Mask" user "Board Geometry/Soldermask Top")
		(3 "B.Mask" user "Board Geometry/Soldermask Bottom")
		(17 "Dwgs.User" user "User.Drawings")
		(19 "Cmts.User" user "User.Comments")
		(21 "Eco1.User" user "User.Eco1")
		(23 "Eco2.User" user "User.Eco2")
		(25 "Edge.Cuts" user "Board Geometry/Outline")
		(27 "Margin" user)
		(31 "F.CrtYd" user "Package Geometry/Place Bound Top")
		(29 "B.CrtYd" user "Package Geometry/Place Bound Bottom")
		(35 "F.Fab" user "Ref Des/Assembly Top")
		(33 "B.Fab" user "Ref Des/Assembly Bottom")
	)
	(footprint ""
		(layer "F.Cu")
		(at 160.377886 -119.089424 180)
		(property "Reference" "R2219"
			(at 0 0 180)
			(layer "F.SilkS")
			(hide yes)
			(effects
				(font
					(size 1.27 1.27)
				)
			)
		)
		(property "Value" ""
			(at 0 0 180)
			(layer "F.Fab")
			(effects
				(font
					(size 1.27 1.27)
				)
			)
		)
		(duplicate_pad_numbers_are_jumpers no)
		(fp_line
			(start 0.7874 0.4064)
			(end -0.7874 0.4064)
			(stroke
				(width 0.1524)
				(type default)
			)
			(layer "F.SilkS")
		)
		(fp_line
			(start 0.7874 -0.4064)
			(end 0.7874 0.4064)
			(stroke
				(width 0.1524)
				(type default)
			)
			(layer "F.SilkS")
		)
		(fp_line
			(start -0.7874 0.4064)
			(end -0.7874 -0.4064)
			(stroke
				(width 0.1524)
				(type default)
			)
			(layer "F.SilkS")
		)
		(fp_line
			(start -0.7874 -0.4064)
			(end 0.7874 -0.4064)
			(stroke
				(width 0.1524)
				(type default)
			)
			(layer "F.SilkS")
		)
		(fp_line
			(start 0.67945 0.3048)
			(end 0.120396 0.3048)
			(stroke
				(width 0.1)
				(type default)
			)
			(layer "F.Fab")
		)
		(fp_line
			(start 0.67945 -0.3048)
			(end 0.67945 0.3048)
			(stroke
				(width 0.1)
				(type default)
			)
			(layer "F.Fab")
		)
		(fp_line
			(start 0.12065 -0.2794)
			(end 0.12065 -0.3048)
			(stroke
				(width 0.1)
				(type default)
			)
			(layer "F.Fab")
		)
		(fp_line
			(start 0.12065 -0.3048)
			(end 0.67945 -0.3048)
			(stroke
				(width 0.1)
				(type default)
			)
			(layer "F.Fab")
		)
		(fp_line
			(start 0.120396 0.3048)
			(end 0.120396 0.2794)
			(stroke
				(width 0.1)
				(type default)
			)
			(layer "F.Fab")
		)
		(fp_line
			(start 0.120396 0.2794)
			(end -0.12065 0.2794)
			(stroke
				(width 0.1)
				(type default)
			)
			(layer "F.Fab")
		)
		(fp_line
			(start -0.12065 0.3048)
			(end -0.67945 0.3048)
			(stroke
				(width 0.1)
				(type default)
			)
			(layer "F.Fab")
		)
		(fp_line
			(start -0.12065 0.2794)
			(end -0.12065 0.3048)
			(stroke
				(width 0.1)
				(type default)
			)
			(layer "F.Fab")
		)
		(fp_line
			(start -0.12065 -0.2794)
			(end 0.12065 -0.2794)
			(stroke
				(width 0.1)
				(type default)
			)
			(layer "F.Fab")
		)
		(fp_line
			(start -0.12065 -0.305054)
			(end -0.12065 -0.2794)
			(stroke
				(width 0.1)
				(type default)
			)
			(layer "F.Fab")
		)
		(fp_line
			(start -0.67945 0.3048)
			(end -0.67945 -0.305054)
			(stroke
				(width 0.1)
				(type default)
			)
			(layer "F.Fab")
		)
		(fp_line
			(start -0.67945 -0.305054)
			(end -0.12065 -0.305054)
			(stroke
				(width 0.1)
				(type default)
			)
			(layer "F.Fab")
		)
		(pad "1" smd circle
			(at -0.40005 0 180)
			(size 0 0)
			(layers "F.Cu" "F.Mask" "F.Paste")
			(net "P12V_AUX")
		)
		(pad "2" smd circle
			(at 0.40005 0 180)
			(size 0 0)
			(layers "F.Cu" "F.Mask" "F.Paste")
			(net "A_P12V_STBY_ADR_TRIGGER")
		)
	)
	(footprint ""
		(layer "F.Cu")
		(at 152.84958 -33.59658)
		(property "Reference" "R1522"
			(at 0 0 0)
			(layer "F.SilkS")
			(hide yes)
			(effects
				(font
					(size 1.27 1.27)
				)
			)
		)
		(property "Value" ""
			(at 0 0 0)
			(layer "F.Fab")
			(effects
				(font
					(size 1.27 1.27)
				)
			)
		)
		(duplicate_pad_numbers_are_jumpers no)
		(fp_line
			(start -0.7874 -0.4064)
			(end 0.7874 -0.4064)
			(stroke
				(width 0.1524)
				(type default)
			)
			(layer "F.SilkS")
		)
		(fp_line
			(start -0.7874 0.4064)
			(end -0.7874 -0.4064)
			(stroke
				(width 0.1524)
				(type default)
			)
			(layer "F.SilkS")
		)
		(fp_line
			(start 0.7874 -0.4064)
			(end 0.7874 0.4064)
			(stroke
				(width 0.1524)
				(type default)
			)
			(layer "F.SilkS")
		)
		(fp_line
			(start 0.7874 0.4064)
			(end -0.7874 0.4064)
			(stroke
				(width 0.1524)
				(type default)
			)
			(layer "F.SilkS")
		)
		(fp_line
			(start -0.67945 -0.305054)
			(end -0.12065 -0.305054)
			(stroke
				(width 0.1)
				(type default)
			)
			(layer "F.Fab")
		)
		(fp_line
			(start -0.67945 0.3048)
			(end -0.67945 -0.305054)
			(stroke
				(width 0.1)
				(type default)
			)
			(layer "F.Fab")
		)
		(fp_line
			(start -0.12065 -0.305054)
			(end -0.12065 -0.2794)
			(stroke
				(width 0.1)
				(type default)
			)
			(layer "F.Fab")
		)
		(fp_line
			(start -0.12065 -0.2794)
			(end 0.12065 -0.2794)
			(stroke
				(width 0.1)
				(type default)
			)
			(layer "F.Fab")
		)
		(fp_line
			(start -0.12065 0.2794)
			(end -0.12065 0.3048)
			(stroke
				(width 0.1)
				(type default)
			)
			(layer "F.Fab")
		)
		(fp_line
			(start -0.12065 0.3048)
			(end -0.67945 0.3048)
			(stroke
				(width 0.1)
				(type default)
			)
			(layer "F.Fab")
		)
		(fp_line
			(start 0.120396 0.2794)
			(end -0.12065 0.2794)
			(stroke
				(width 0.1)
				(type default)
			)
			(layer "F.Fab")
		)
		(fp_line
			(start 0.120396 0.3048)
			(end 0.120396 0.2794)
			(stroke
				(width 0.1)
				(type default)
			)
			(layer "F.Fab")
		)
		(fp_line
			(start 0.12065 -0.3048)
			(end 0.67945 -0.3048)
			(stroke
				(width 0.1)
				(type default)
			)
			(layer "F.Fab")
		)
		(fp_line
			(start 0.12065 -0.2794)
			(end 0.12065 -0.3048)
			(stroke
				(width 0.1)
				(type default)
			)
			(layer "F.Fab")
		)
		(fp_line
			(start 0.67945 -0.3048)
			(end 0.67945 0.3048)
			(stroke
				(width 0.1)
				(type default)
			)
			(layer "F.Fab")
		)
		(fp_line
			(start 0.67945 0.3048)
			(end 0.120396 0.3048)
			(stroke
				(width 0.1)
				(type default)
			)
			(layer "F.Fab")
		)
		(pad "1" smd circle
			(at -0.40005 0)
			(size 0 0)
			(layers "F.Cu" "F.Mask" "F.Paste")
			(net "HP_LVC3_OCP_V3_2_R_EN")
		)
		(pad "2" smd circle
			(at 0.40005 0)
			(size 0 0)
			(layers "F.Cu" "F.Mask" "F.Paste")
			(net "P12V_OCP_V3_2_BUF_EN_R")
		)
	)
	(footprint ""
		(layer "F.Cu")
		(at 429.4251 -400.987768 -90)
		(property "Reference" "R1057"
			(at 0 0 270)
			(layer "F.SilkS")
			(hide yes)
			(effects
				(font
					(size 1.27 1.27)
				)
			)
		)
		(property "Value" ""
			(at 0 0 270)
			(layer "F.Fab")
			(effects
				(font
					(size 1.27 1.27)
				)
			)
		)
		(duplicate_pad_numbers_are_jumpers no)
		(fp_line
			(start -0.32512 0.175006)
			(end -0.32512 -0.175006)
			(stroke
				(width 0.1)
				(type default)
			)
			(layer "F.Fab")
		)
		(fp_line
			(start 0.32512 0.175006)
			(end -0.32512 0.175006)
			(stroke
				(width 0.1)
				(type default)
			)
			(layer "F.Fab")
		)
		(fp_line
			(start -0.32512 -0.175006)
			(end 0.32512 -0.175006)
			(stroke
				(width 0.1)
				(type default)
			)
			(layer "F.Fab")
		)
		(fp_line
			(start 0.32512 -0.175006)
			(end 0.32512 0.175006)
			(stroke
				(width 0.1)
				(type default)
			)
			(layer "F.Fab")
		)
		(pad "1" smd rect
			(at -0.2667 0 270)
			(size 0.3048 0.381)
			(layers "F.Cu" "F.Mask" "F.Paste")
			(net "P1V8_CPU0_RT_1D")
		)
		(pad "2" smd rect
			(at 0.2667 0 90)
			(size 0.3048 0.381)
			(layers "F.Cu" "F.Mask" "F.Paste")
			(net "RT_CPU0_P2_ADDR2")
		)
	)
)
